# BASEBOARD_FAB2 (Tioga Pass) — schematic netlist excerpt (pin names and nets, part order shuffled) for the footprints in the layout excerpt that follows; sources: Cadence DE-HDL packaged netlist, KiCad conversion of Wiwynn_Tioga_Pass_MB.brd

EU7B1  NCP3232L  IC  pkg SM  page 232
  SS  = VR_PVPP_DEF_SS
  FB  = VR_FB_PVPP_DEF
  COMP  = VR_COMP_PVPP_DEF_3
  ISET  = VR_PVPP_DEF_ISET
  AGND  = AGND_PVPP_DEF
  OTS  = AGND_PVPP_DEF
  PG  = PWRGD_PVPP_DEF_R
  VIN(0)  = VR_FET_SW_P12V_STBY_PVPP_DEF
  VIN(1)  = VR_FET_SW_P12V_STBY_PVPP_DEF
  VIN(2)  = VR_FET_SW_P12V_STBY_PVPP_DEF
  VIN(3)  = VR_FET_SW_P12V_STBY_PVPP_DEF
  VIN(4)  = VR_FET_SW_P12V_STBY_PVPP_DEF
  VIN(5)  = VR_FET_SW_P12V_STBY_PVPP_DEF
  VIN(6)  = VR_FET_SW_P12V_STBY_PVPP_DEF
  VSWH(0)  = VR_PVPP_DEF_PHASE
  PGND(0)  = GND
  PGND(1)  = GND
  PGND(2)  = GND
  PGND(3)  = GND
  PGND(4)  = GND
  PGND(5)  = GND
  PGND(6)  = GND
  PGND(7)  = GND
  PGND(8)  = GND
  PGND(9)  = GND
  PGND(10)  = GND
  PGND(11)  = GND
  PGND(12)  = GND
  VSWH(1)  = VR_PVPP_DEF_PHASE
  VSWH(2)  = VR_PVPP_DEF_PHASE
  VSWH(3)  = VR_PVPP_DEF_PHASE
  VSWH(4)  = VR_PVPP_DEF_PHASE
  VSWH(5)  = VR_PVPP_DEF_PHASE
  VSWH(6)  = VR_PVPP_DEF_PHASE
  VSW  = VR_PVPP_DEF_PHASE
  BST  = VR_PVPP_DEF_BOOT
  PGND(13)  = GND
  VB  = VR_VB_PVPP_DEF
  VCC  = VR_FET_SW_P12V_STBY_PVPP_DEF
  EN  = FM_PVPP_PVDDQ_CPU0_EN_DEF
  GND  = GND
  VIN(7)  = VR_FET_SW_P12V_STBY_PVPP_DEF
  VSWH(7)  = VR_PVPP_DEF_PHASE

(kicad_pcb
	(version 20260206)
	(generator "pcbnew")
	(generator_version "10.0")
	(general
		(thickness 1.6)
		(legacy_teardrops no)
	)
	(paper "A4")
	(title_block
		(title "Wiwynn_Tioga_Pass_MB.brd")
		(comment 1 "Tioga Pass / footprint 1728 of 4770 (EU7B1), pads 36-43 of 43")
	)
	(layers
		(0 "F.Cu" signal "TOP")
		(4 "In1.Cu" signal "L2GND")
		(6 "In2.Cu" signal "L3")
		(8 "In3.Cu" signal "L4GND")
		(10 "In4.Cu" signal "L5")
		(12 "In5.Cu" signal "L6GND")
		(14 "In6.Cu" signal "L7VCC")
		(16 "In7.Cu" signal "L8VCC")
		(18 "In8.Cu" signal "L9GND")
		(20 "In9.Cu" signal "L10")
		(22 "In10.Cu" signal "L11GND")
		(24 "In11.Cu" signal "L12")
		(26 "In12.Cu" signal "L13GND")
		(2 "B.Cu" signal "BOTTOM")
		(9 "F.Adhes" user "F.Adhesive")
		(11 "B.Adhes" user "B.Adhesive")
		(13 "F.Paste" user "Package Geometry/Pastemask Top")
		(15 "B.Paste" user "Package Geometry/Pastemask Bottom")
		(5 "F.SilkS" user "Ref Des/Silkscreen Top")
		(7 "B.SilkS" user "Ref Des/Silkscreen Bottom")
		(1 "F.Mask" user "Board Geometry/Soldermask Top")
		(3 "B.Mask" user "Board Geometry/Soldermask Bottom")
		(17 "Dwgs.User" user "User.Drawings")
		(19 "Cmts.User" user "User.Comments")
		(21 "Eco1.User" user "User.Eco1")
		(23 "Eco2.User" user "User.Eco2")
		(25 "Edge.Cuts" user "Board Geometry/Outline")
		(27 "Margin" user)
		(31 "F.CrtYd" user "Package Geometry/Place Bound Top")
		(29 "B.CrtYd" user "Package Geometry/Place Bound Bottom")
		(35 "F.Fab" user "Ref Des/Assembly Top")
		(33 "B.Fab" user "Ref Des/Assembly Bottom")
	)
	(footprint ""
		(layer "F.Cu")
		(at 344.043 -132.8547 90)
		(property "Reference" "EU7B1"
			(at 5.29463 -1.27 0)
			(unlocked yes)
			(layer "F.SilkS")
			(effects
				(font
					(size 0.7874 0.5842)
					(thickness 0.1524)
				)
				(justify left)
			)
		)
		(property "Value" ""
			(at 0 0 90)
			(layer "F.Fab")
			(effects
				(font
					(size 1.27 1.27)
				)
			)
		)
		(duplicate_pad_numbers_are_jumpers no)
		(pad "36" smd custom
			(at -0.249936 -2.8321 90)
			(size 0.06985 0.06985)
			(layers "F.Cu" "F.Mask" "F.Paste")
			(net "VR_PVPP_DEF_BOOT")
			(options
				(clearance outline)
				(anchor circle)
			)
			(primitives
				(gr_poly
					(pts
						(arc
							(start 0.1397 0.2413)
							(mid 0 0.381)
							(end -0.1397 0.2413)
						)
						(xy -0.1397 -0.381) (xy 0.1397 -0.381)
					)
					(width 0)
					(fill yes)
				)
			)
		)
		(pad "37" smd custom
			(at -0.750062 -2.8321 90)
			(size 0.06985 0.06985)
			(layers "F.Cu" "F.Mask" "F.Paste")
			(net "GND")
			(options
				(clearance outline)
				(anchor circle)
			)
			(primitives
				(gr_poly
					(pts
						(arc
							(start 0.1397 0.2413)
							(mid 0 0.381)
							(end -0.1397 0.2413)
						)
						(xy -0.1397 -0.381) (xy 0.1397 -0.381)
					)
					(width 0)
					(fill yes)
				)
			)
		)
		(pad "38" smd custom
			(at -1.249934 -2.8321 90)
			(size 0.06985 0.06985)
			(layers "F.Cu" "F.Mask" "F.Paste")
			(net "VR_VB_PVPP_DEF")
			(options
				(clearance outline)
				(anchor circle)
			)
			(primitives
				(gr_poly
					(pts
						(arc
							(start 0.1397 0.2413)
							(mid 0 0.381)
							(end -0.1397 0.2413)
						)
						(xy -0.1397 -0.381) (xy 0.1397 -0.381)
					)
					(width 0)
					(fill yes)
				)
			)
		)
		(pad "39" smd custom
			(at -1.75006 -2.8321 90)
			(size 0.06985 0.06985)
			(layers "F.Cu" "F.Mask" "F.Paste")
			(net "VR_FET_SW_P12V_STBY_PVPP_DEF")
			(options
				(clearance outline)
				(anchor circle)
			)
			(primitives
				(gr_poly
					(pts
						(arc
							(start 0.1397 0.2413)
							(mid 0 0.381)
							(end -0.1397 0.2413)
						)
						(xy -0.1397 -0.381) (xy 0.1397 -0.381)
					)
					(width 0)
					(fill yes)
				)
			)
		)
		(pad "40" smd custom
			(at -2.249932 -2.8321 90)
			(size 0.06985 0.06985)
			(layers "F.Cu" "F.Mask" "F.Paste")
			(net "FM_PVPP_PVDDQ_CPU0_EN_DEF")
			(options
				(clearance outline)
				(anchor circle)
			)
			(primitives
				(gr_poly
					(pts
						(arc
							(start 0.1397 0.2413)
							(mid 0 0.381)
							(end -0.1397 0.2413)
						)
						(xy -0.1397 -0.381) (xy 0.1397 -0.381)
					)
					(width 0)
					(fill yes)
				)
			)
		)
		(pad "41" smd rect
			(at -1.4478 -1.1938 90)
			(size 1.4986 2.0066)
			(layers "F.Cu" "F.Mask" "F.Paste")
			(net "GND")
		)
		(pad "42" smd rect
			(at -1.4478 1.1938 90)
			(size 1.4986 2.0066)
			(layers "F.Cu" "F.Mask" "F.Paste")
			(net "VR_FET_SW_P12V_STBY_PVPP_DEF")
		)
		(pad "43" smd rect
			(at 1.0033 0 90)
			(size 2.3876 4.3942)
			(layers "F.Cu" "F.Mask" "F.Paste")
			(net "VR_PVPP_DEF_PHASE")
		)
	)
)
